FILE_TYPE = MULTI_PHYS_TABLE;

PART '74LVC2G08DP'

{========================================================================================}
:VALUE         | PART_TYPE | MATERIAL | PART_NUMBER    = STANDARD | LIFECYCLE      | PART_NUMBER   | JEDEC_TYPE        | DESCRIPTION                       | MANUFTR | MANUF_PN      | RD_CMPLS_LVL | CMPLS_LVL | FROM_PJ    | CLASS | DIP_SMD | DATA                  | EE_CHECK_LIST | FP_ECN | PSL | CREATOR | STATUS | MSD | ESD_CDM | ESD_HBM | ESD_MM | PIN_LENGTH_SHORT_PIN | PIN_LENGTH_LONG_PIN | CREATEDAY  ;
{========================================================================================}
 '74LVC2G08DP' | 'SMLF'    | 'IC'     | 'ALVC2G08K01'(!) = ''       | ''               | 'ALVC2G08K01' |'TSSOP8_0-65_3X3'| 'IC OTHER(8P) 74LVC2G08DP(TSSOP)' | 'NXP'   | '74LVC2G08DP' | 'EP(V1)'     | 'EP(V1)'  | 'F08-OWEN' | 'IC'  | ''      | 'NXP_74LVC2G08DP.pdf' | ''            | ''     | ''  | ''      | ''     | ''  | ''      | ''      | ''     | ''                   | ''                  | '20160122'
 '74LVC2G08DP' | 'SMLF'    | 'EMPTY'  | 'ALVC2G08K01'(!) = ''       | ''               | 'ALVC2G08K01' |'TSSOP8_0-65_3X3'| 'IC OTHER(8P) 74LVC2G08DP(TSSOP)' | 'NXP'   | '74LVC2G08DP' | 'EP(V1)'     | 'EP(V1)'  | 'F08-OWEN' | 'IC'  | ''      | 'NXP_74LVC2G08DP.pdf' | ''            | ''     | ''  | ''      | ''     | ''  | ''      | ''      | ''     | ''                   | ''                  | '20160122'

END_PART

END.

